(kicad_pcb
	(version 20260206)
	(generator "pcbnew")
	(generator_version "10.0")
	(general
		(thickness 1.6)
		(legacy_teardrops no)
	)
	(paper "A4")
	(title_block
		(title "04192023_DAF0TMB3IC0_F0TG_MB_C_brd_V02_OCP.brd")
		(comment 1 "Grand Teton / footprints 7846-7852 of 8354")
	)
	(layers
		(0 "F.Cu" signal "TOP")
		(4 "In1.Cu" signal "GND")
		(6 "In2.Cu" signal "IN1")
		(8 "In3.Cu" signal "GND1")
		(10 "In4.Cu" signal "IN2")
		(12 "In5.Cu" signal "GND2")
		(14 "In6.Cu" signal "IN3")
		(16 "In7.Cu" signal "GND3")
		(18 "In8.Cu" signal "VCC")
		(20 "In9.Cu" signal "VCC1")
		(22 "In10.Cu" signal "GND4")
		(24 "In11.Cu" signal "IN4")
		(26 "In12.Cu" signal "GND5")
		(28 "In13.Cu" signal "IN5")
		(30 "In14.Cu" signal "GND6")
		(32 "In15.Cu" signal "IN6")
		(34 "In16.Cu" signal "GND7")
		(2 "B.Cu" signal "BOTTOM")
		(9 "F.Adhes" user "F.Adhesive")
		(11 "B.Adhes" user "B.Adhesive")
		(13 "F.Paste" user "Package Geometry/Pastemask Top")
		(15 "B.Paste" user "Package Geometry/Pastemask Bottom")
		(5 "F.SilkS" user "Ref Des/Silkscreen Top")
		(7 "B.SilkS" user "Ref Des/Silkscreen Bottom")
		(1 "F.Mask" user "Board Geometry/Soldermask Top")
		(3 "B.Mask" user "Board Geometry/Soldermask Bottom")
		(17 "Dwgs.User" user "User.Drawings")
		(19 "Cmts.User" user "User.Comments")
		(21 "Eco1.User" user "User.Eco1")
		(23 "Eco2.User" user "User.Eco2")
		(25 "Edge.Cuts" user "Board Geometry/Outline")
		(27 "Margin" user)
		(31 "F.CrtYd" user "Package Geometry/Place Bound Top")
		(29 "B.CrtYd" user "Package Geometry/Place Bound Bottom")
		(35 "F.Fab" user "Ref Des/Assembly Top")
		(33 "B.Fab" user "Ref Des/Assembly Bottom")
	)
	(footprint ""
		(layer "B.Cu")
		(at 473.874592 -202.415902 180)
		(property "Reference" "DB13"
			(at 2.443988 -8.440928 270)
			(unlocked yes)
			(layer "B.SilkS")
			(effects
				(font
					(size 0.7874 0.5842)
					(thickness 0.1524)
				)
				(justify left mirror)
			)
		)
		(property "Value" ""
			(at 0 0 0)
			(layer "B.Fab")
			(effects
				(font
					(size 1.27 1.27)
				)
				(justify mirror)
			)
		)
		(duplicate_pad_numbers_are_jumpers no)
		(fp_line
			(start 3.330702 -4.771136)
			(end -3.330702 -4.771136)
			(stroke
				(width 0.1524)
				(type default)
			)
			(layer "B.SilkS")
		)
		(fp_line
			(start 0 4.011168)
			(end 3.330702 -4.771136)
			(stroke
				(width 0.1524)
				(type default)
			)
			(layer "B.SilkS")
		)
		(fp_line
			(start -3.330702 -4.771136)
			(end 0 4.011168)
			(stroke
				(width 0.1524)
				(type default)
			)
			(layer "B.SilkS")
		)
		(fp_line
			(start 3.330702 -4.771136)
			(end -3.330702 -4.771136)
			(stroke
				(width 0.1)
				(type default)
			)
			(layer "B.Fab")
		)
		(fp_line
			(start 0 4.011168)
			(end 3.330702 -4.771136)
			(stroke
				(width 0.1)
				(type default)
			)
			(layer "B.Fab")
		)
		(fp_line
			(start -3.330702 -4.771136)
			(end 0 4.011168)
			(stroke
				(width 0.1)
				(type default)
			)
			(layer "B.Fab")
		)
		(pad "1" thru_hole circle
			(at 0 0)
			(size 2.159 2.159)
			(drill 1.7018)
			(layers "*.Cu" "*.Mask")
			(remove_unused_layers no)
			(net "T1_GND")
			(clearance 0.0254)
			(thermal_gap 0.0254)
		)
		(pad "2" thru_hole circle
			(at 1.27 -3.348736)
			(size 2.159 2.159)
			(drill 1.7018)
			(layers "*.Cu" "*.Mask")
			(remove_unused_layers no)
			(net "TDR_SE_45_OHM_IN5")
			(clearance 0.0254)
			(thermal_gap 0.0254)
		)
		(pad "3" thru_hole circle
			(at -1.27 -3.348736)
			(size 2.159 2.159)
			(drill 1.7018)
			(layers "*.Cu" "*.Mask")
			(remove_unused_layers no)
			(net "TDR_SE_45_OHM_IN5")
			(clearance 0.0254)
			(thermal_gap 0.0254)
		)
	)
	(footprint ""
		(layer "B.Cu")
		(at 182.801768 -413.743394 180)
		(property "Reference" "R2917"
			(at 0 0 0)
			(layer "B.SilkS")
			(hide yes)
			(effects
				(font
					(size 1.27 1.27)
				)
				(justify mirror)
			)
		)
		(property "Value" ""
			(at 0 0 0)
			(layer "B.Fab")
			(effects
				(font
					(size 1.27 1.27)
				)
				(justify mirror)
			)
		)
		(duplicate_pad_numbers_are_jumpers no)
		(fp_line
			(start 0.7874 0.4064)
			(end 0.7874 -0.4064)
			(stroke
				(width 0.1524)
				(type default)
			)
			(layer "B.SilkS")
		)
		(fp_line
			(start 0.7874 -0.4064)
			(end -0.7874 -0.4064)
			(stroke
				(width 0.1524)
				(type default)
			)
			(layer "B.SilkS")
		)
		(fp_line
			(start -0.7874 0.4064)
			(end 0.7874 0.4064)
			(stroke
				(width 0.1524)
				(type default)
			)
			(layer "B.SilkS")
		)
		(fp_line
			(start -0.7874 -0.4064)
			(end -0.7874 0.4064)
			(stroke
				(width 0.1524)
				(type default)
			)
			(layer "B.SilkS")
		)
		(fp_line
			(start 0.67945 0.3048)
			(end 0.67945 -0.305054)
			(stroke
				(width 0.1)
				(type default)
			)
			(layer "B.Fab")
		)
		(fp_line
			(start 0.67945 -0.305054)
			(end 0.12065 -0.305054)
			(stroke
				(width 0.1)
				(type default)
			)
			(layer "B.Fab")
		)
		(fp_line
			(start 0.12065 0.3048)
			(end 0.67945 0.3048)
			(stroke
				(width 0.1)
				(type default)
			)
			(layer "B.Fab")
		)
		(fp_line
			(start 0.12065 0.2794)
			(end 0.12065 0.3048)
			(stroke
				(width 0.1)
				(type default)
			)
			(layer "B.Fab")
		)
		(fp_line
			(start 0.12065 -0.2794)
			(end -0.12065 -0.2794)
			(stroke
				(width 0.1)
				(type default)
			)
			(layer "B.Fab")
		)
		(fp_line
			(start 0.12065 -0.305054)
			(end 0.12065 -0.2794)
			(stroke
				(width 0.1)
				(type default)
			)
			(layer "B.Fab")
		)
		(fp_line
			(start -0.120396 0.3048)
			(end -0.120396 0.2794)
			(stroke
				(width 0.1)
				(type default)
			)
			(layer "B.Fab")
		)
		(fp_line
			(start -0.120396 0.2794)
			(end 0.12065 0.2794)
			(stroke
				(width 0.1)
				(type default)
			)
			(layer "B.Fab")
		)
		(fp_line
			(start -0.12065 -0.2794)
			(end -0.12065 -0.3048)
			(stroke
				(width 0.1)
				(type default)
			)
			(layer "B.Fab")
		)
		(fp_line
			(start -0.12065 -0.3048)
			(end -0.67945 -0.3048)
			(stroke
				(width 0.1)
				(type default)
			)
			(layer "B.Fab")
		)
		(fp_line
			(start -0.67945 0.3048)
			(end -0.120396 0.3048)
			(stroke
				(width 0.1)
				(type default)
			)
			(layer "B.Fab")
		)
		(fp_line
			(start -0.67945 -0.3048)
			(end -0.67945 0.3048)
			(stroke
				(width 0.1)
				(type default)
			)
			(layer "B.Fab")
		)
		(pad "1" smd circle
			(at 0.40005 0)
			(size 0 0)
			(layers "B.Cu" "B.Mask" "B.Paste")
			(net "BMC_MONITER_BUF_R")
		)
		(pad "2" smd circle
			(at -0.40005 0)
			(size 0 0)
			(layers "B.Cu" "B.Mask" "B.Paste")
			(net "BMC_MONITER_BUF")
		)
	)
	(footprint ""
		(layer "B.Cu")
		(at 19.748246 -383.038096 -90)
		(property "Reference" "PC6643_2"
			(at 0 0 90)
			(layer "B.SilkS")
			(hide yes)
			(effects
				(font
					(size 1.27 1.27)
				)
				(justify mirror)
			)
		)
		(property "Value" ""
			(at 0 0 90)
			(layer "B.Fab")
			(effects
				(font
					(size 1.27 1.27)
				)
				(justify mirror)
			)
		)
		(duplicate_pad_numbers_are_jumpers no)
		(fp_line
			(start -1.524 0.762)
			(end 1.524 0.762)
			(stroke
				(width 0.1524)
				(type default)
			)
			(layer "B.SilkS")
		)
		(fp_line
			(start 1.524 0.762)
			(end 1.524 -0.762)
			(stroke
				(width 0.1524)
				(type default)
			)
			(layer "B.SilkS")
		)
		(fp_line
			(start -1.524 -0.762)
			(end -1.524 0.762)
			(stroke
				(width 0.1524)
				(type default)
			)
			(layer "B.SilkS")
		)
		(fp_line
			(start 1.524 -0.762)
			(end -1.524 -0.762)
			(stroke
				(width 0.1524)
				(type default)
			)
			(layer "B.SilkS")
		)
		(fp_line
			(start -1.1049 0.724916)
			(end -1.1049 -0.724916)
			(stroke
				(width 0.1)
				(type default)
			)
			(layer "B.Fab")
		)
		(fp_line
			(start 1.1049 0.724916)
			(end -1.1049 0.724916)
			(stroke
				(width 0.1)
				(type default)
			)
			(layer "B.Fab")
		)
		(fp_line
			(start -1.1049 -0.724916)
			(end 1.1049 -0.724916)
			(stroke
				(width 0.1)
				(type default)
			)
			(layer "B.Fab")
		)
		(fp_line
			(start 1.1049 -0.724916)
			(end 1.1049 0.724916)
			(stroke
				(width 0.1)
				(type default)
			)
			(layer "B.Fab")
		)
		(pad "1" smd rect
			(at 0.889 0 270)
			(size 1.016 1.27)
			(layers "B.Cu" "B.Mask" "B.Paste")
			(net "P0V9_CPU1_RT_2D")
		)
		(pad "2" smd rect
			(at -0.889 0 270)
			(size 1.016 1.27)
			(layers "B.Cu" "B.Mask" "B.Paste")
			(net "GND")
		)
	)
	(footprint ""
		(layer "B.Cu")
		(at 438.344564 -194.893946 180)
		(property "Reference" "R1577"
			(at 0 0 0)
			(layer "B.SilkS")
			(hide yes)
			(effects
				(font
					(size 1.27 1.27)
				)
				(justify mirror)
			)
		)
		(property "Value" ""
			(at 0 0 0)
			(layer "B.Fab")
			(effects
				(font
					(size 1.27 1.27)
				)
				(justify mirror)
			)
		)
		(duplicate_pad_numbers_are_jumpers no)
		(fp_line
			(start 0.7874 0.4064)
			(end 0.7874 -0.4064)
			(stroke
				(width 0.1524)
				(type default)
			)
			(layer "B.SilkS")
		)
		(fp_line
			(start 0.7874 -0.4064)
			(end -0.7874 -0.4064)
			(stroke
				(width 0.1524)
				(type default)
			)
			(layer "B.SilkS")
		)
		(fp_line
			(start -0.7874 0.4064)
			(end 0.7874 0.4064)
			(stroke
				(width 0.1524)
				(type default)
			)
			(layer "B.SilkS")
		)
		(fp_line
			(start -0.7874 -0.4064)
			(end -0.7874 0.4064)
			(stroke
				(width 0.1524)
				(type default)
			)
			(layer "B.SilkS")
		)
		(fp_line
			(start 0.67945 0.3048)
			(end 0.67945 -0.305054)
			(stroke
				(width 0.1)
				(type default)
			)
			(layer "B.Fab")
		)
		(fp_line
			(start 0.67945 -0.305054)
			(end 0.12065 -0.305054)
			(stroke
				(width 0.1)
				(type default)
			)
			(layer "B.Fab")
		)
		(fp_line
			(start 0.12065 0.3048)
			(end 0.67945 0.3048)
			(stroke
				(width 0.1)
				(type default)
			)
			(layer "B.Fab")
		)
		(fp_line
			(start 0.12065 0.2794)
			(end 0.12065 0.3048)
			(stroke
				(width 0.1)
				(type default)
			)
			(layer "B.Fab")
		)
		(fp_line
			(start 0.12065 -0.2794)
			(end -0.12065 -0.2794)
			(stroke
				(width 0.1)
				(type default)
			)
			(layer "B.Fab")
		)
		(fp_line
			(start 0.12065 -0.305054)
			(end 0.12065 -0.2794)
			(stroke
				(width 0.1)
				(type default)
			)
			(layer "B.Fab")
		)
		(fp_line
			(start -0.120396 0.3048)
			(end -0.120396 0.2794)
			(stroke
				(width 0.1)
				(type default)
			)
			(layer "B.Fab")
		)
		(fp_line
			(start -0.120396 0.2794)
			(end 0.12065 0.2794)
			(stroke
				(width 0.1)
				(type default)
			)
			(layer "B.Fab")
		)
		(fp_line
			(start -0.12065 -0.2794)
			(end -0.12065 -0.3048)
			(stroke
				(width 0.1)
				(type default)
			)
			(layer "B.Fab")
		)
		(fp_line
			(start -0.12065 -0.3048)
			(end -0.67945 -0.3048)
			(stroke
				(width 0.1)
				(type default)
			)
			(layer "B.Fab")
		)
		(fp_line
			(start -0.67945 0.3048)
			(end -0.120396 0.3048)
			(stroke
				(width 0.1)
				(type default)
			)
			(layer "B.Fab")
		)
		(fp_line
			(start -0.67945 -0.3048)
			(end -0.67945 0.3048)
			(stroke
				(width 0.1)
				(type default)
			)
			(layer "B.Fab")
		)
		(pad "1" smd circle
			(at 0.40005 0)
			(size 0 0)
			(layers "B.Cu" "B.Mask" "B.Paste")
			(net "I3C_SPD_DDRGL_CPU0_SCL")
		)
		(pad "2" smd circle
			(at -0.40005 0)
			(size 0 0)
			(layers "B.Cu" "B.Mask" "B.Paste")
			(net "I3C_SPD_DDRJ_CPU0_SCL")
		)
	)
	(footprint ""
		(layer "B.Cu")
		(at 348.04604 -396.393162 -90)
		(property "Reference" "C615"
			(at 0 0 90)
			(layer "B.SilkS")
			(hide yes)
			(effects
				(font
					(size 1.27 1.27)
				)
				(justify mirror)
			)
		)
		(property "Value" ""
			(at 0 0 90)
			(layer "B.Fab")
			(effects
				(font
					(size 1.27 1.27)
				)
				(justify mirror)
			)
		)
		(duplicate_pad_numbers_are_jumpers no)
		(fp_line
			(start -0.299974 0.150114)
			(end 0.299974 0.150114)
			(stroke
				(width 0.1)
				(type default)
			)
			(layer "B.Fab")
		)
		(fp_line
			(start 0.299974 0.150114)
			(end 0.299974 -0.150114)
			(stroke
				(width 0.1)
				(type default)
			)
			(layer "B.Fab")
		)
		(fp_line
			(start -0.299974 -0.150114)
			(end -0.299974 0.150114)
			(stroke
				(width 0.1)
				(type default)
			)
			(layer "B.Fab")
		)
		(fp_line
			(start 0.299974 -0.150114)
			(end -0.299974 -0.150114)
			(stroke
				(width 0.1)
				(type default)
			)
			(layer "B.Fab")
		)
		(pad "1" smd rect
			(at 0.2667 0 90)
			(size 0.3048 0.381)
			(layers "B.Cu" "B.Mask" "B.Paste")
			(net "P0V9_CPU0_RT_2D")
		)
		(pad "2" smd rect
			(at -0.2667 0 90)
			(size 0.3048 0.381)
			(layers "B.Cu" "B.Mask" "B.Paste")
			(net "GND")
		)
	)
	(footprint ""
		(layer "B.Cu")
		(at 332.464664 -73.534778)
		(property "Reference" "Q81"
			(at 1.4859 2.394712 0)
			(unlocked yes)
			(layer "B.SilkS")
			(effects
				(font
					(size 0.7874 0.5842)
					(thickness 0.1524)
				)
				(justify left mirror)
			)
		)
		(property "Value" ""
			(at 0 0 0)
			(layer "B.Fab")
			(effects
				(font
					(size 1.27 1.27)
				)
				(justify mirror)
			)
		)
		(duplicate_pad_numbers_are_jumpers no)
		(fp_line
			(start -1.332738 -1.100074)
			(end -1.332738 1.100074)
			(stroke
				(width 0.1524)
				(type default)
			)
			(layer "B.SilkS")
		)
		(fp_line
			(start -1.332738 1.100074)
			(end 1.332738 1.100074)
			(stroke
				(width 0.1524)
				(type default)
			)
			(layer "B.SilkS")
		)
		(fp_line
			(start -0.4826 -1.100074)
			(end -1.332738 -1.100074)
			(stroke
				(width 0.1524)
				(type default)
			)
			(layer "B.SilkS")
		)
		(fp_line
			(start 0 -0.541274)
			(end -0.4826 -1.100074)
			(stroke
				(width 0.1524)
				(type default)
			)
			(layer "B.SilkS")
		)
		(fp_line
			(start 0.4826 -1.100074)
			(end 0 -0.541274)
			(stroke
				(width 0.1524)
				(type default)
			)
			(layer "B.SilkS")
		)
		(fp_line
			(start 1.332738 -1.100074)
			(end 0.4826 -1.100074)
			(stroke
				(width 0.1524)
				(type default)
			)
			(layer "B.SilkS")
		)
		(fp_line
			(start 1.332738 1.100074)
			(end 1.332738 -1.100074)
			(stroke
				(width 0.1524)
				(type default)
			)
			(layer "B.SilkS")
		)
		(fp_poly
			(pts
				(xy 1.533144 -0.649986) (xy 2.2352 -1.001014) (xy 2.2352 -0.298958)
			)
			(stroke
				(width 0)
				(type default)
			)
			(fill yes)
			(layer "B.SilkS")
		)
		(fp_line
			(start -0.674878 -1.100074)
			(end -0.674878 1.100074)
			(stroke
				(width 0.1)
				(type default)
			)
			(layer "B.Fab")
		)
		(fp_line
			(start -0.674878 1.100074)
			(end 0.674878 1.100074)
			(stroke
				(width 0.1)
				(type default)
			)
			(layer "B.Fab")
		)
		(fp_line
			(start 0.674878 -1.100074)
			(end -0.674878 -1.100074)
			(stroke
				(width 0.1)
				(type default)
			)
			(layer "B.Fab")
		)
		(fp_line
			(start 0.674878 1.100074)
			(end 0.674878 -1.100074)
			(stroke
				(width 0.1)
				(type default)
			)
			(layer "B.Fab")
		)
		(fp_poly
			(pts
				(xy 2.2352 -0.298958) (xy 2.2352 -1.001014) (xy 1.533144 -0.649986)
			)
			(stroke
				(width 0)
				(type default)
			)
			(fill yes)
			(layer "B.Fab")
		)
		(pad "1" smd rect
			(at 0.94996 -0.649986 90)
			(size 0.4318 0.508)
			(layers "B.Cu" "B.Mask" "B.Paste")
			(net "GND")
		)
		(pad "2" smd rect
			(at 0.94996 0 90)
			(size 0.4318 0.508)
			(layers "B.Cu" "B.Mask" "B.Paste")
			(net "FM_LED_PWRGD_PVDDIO_P0")
		)
		(pad "3" smd rect
			(at 0.94996 0.649986 90)
			(size 0.4318 0.508)
			(layers "B.Cu" "B.Mask" "B.Paste")
			(net "LED_PWRGD_PVDD11_S3_P0_D")
		)
		(pad "4" smd rect
			(at -0.94996 0.649986 90)
			(size 0.4318 0.508)
			(layers "B.Cu" "B.Mask" "B.Paste")
			(net "GND")
		)
		(pad "5" smd rect
			(at -0.94996 0 90)
			(size 0.4318 0.508)
			(layers "B.Cu" "B.Mask" "B.Paste")
			(net "FM_LED_PWRGD_PVDD11_S3_P0")
		)
		(pad "6" smd rect
			(at -0.94996 -0.649986 90)
			(size 0.4318 0.508)
			(layers "B.Cu" "B.Mask" "B.Paste")
			(net "LED_PWRGD_PVDDIO_P0_D")
		)
	)
	(footprint ""
		(layer "B.Cu")
		(at 171.976288 -427.923706 180)
		(property "Reference" "R6236"
			(at 0 0 0)
			(layer "B.SilkS")
			(hide yes)
			(effects
				(font
					(size 1.27 1.27)
				)
				(justify mirror)
			)
		)
		(property "Value" ""
			(at 0 0 0)
			(layer "B.Fab")
			(effects
				(font
					(size 1.27 1.27)
				)
				(justify mirror)
			)
		)
		(duplicate_pad_numbers_are_jumpers no)
		(fp_line
			(start 0.7874 0.4064)
			(end 0.7874 -0.4064)
			(stroke
				(width 0.1524)
				(type default)
			)
			(layer "B.SilkS")
		)
		(fp_line
			(start 0.7874 -0.4064)
			(end -0.7874 -0.4064)
			(stroke
				(width 0.1524)
				(type default)
			)
			(layer "B.SilkS")
		)
		(fp_line
			(start -0.7874 0.4064)
			(end 0.7874 0.4064)
			(stroke
				(width 0.1524)
				(type default)
			)
			(layer "B.SilkS")
		)
		(fp_line
			(start -0.7874 -0.4064)
			(end -0.7874 0.4064)
			(stroke
				(width 0.1524)
				(type default)
			)
			(layer "B.SilkS")
		)
		(fp_line
			(start 0.67945 0.3048)
			(end 0.67945 -0.305054)
			(stroke
				(width 0.1)
				(type default)
			)
			(layer "B.Fab")
		)
		(fp_line
			(start 0.67945 -0.305054)
			(end 0.12065 -0.305054)
			(stroke
				(width 0.1)
				(type default)
			)
			(layer "B.Fab")
		)
		(fp_line
			(start 0.12065 0.3048)
			(end 0.67945 0.3048)
			(stroke
				(width 0.1)
				(type default)
			)
			(layer "B.Fab")
		)
		(fp_line
			(start 0.12065 0.2794)
			(end 0.12065 0.3048)
			(stroke
				(width 0.1)
				(type default)
			)
			(layer "B.Fab")
		)
		(fp_line
			(start 0.12065 -0.2794)
			(end -0.12065 -0.2794)
			(stroke
				(width 0.1)
				(type default)
			)
			(layer "B.Fab")
		)
		(fp_line
			(start 0.12065 -0.305054)
			(end 0.12065 -0.2794)
			(stroke
				(width 0.1)
				(type default)
			)
			(layer "B.Fab")
		)
		(fp_line
			(start -0.120396 0.3048)
			(end -0.120396 0.2794)
			(stroke
				(width 0.1)
				(type default)
			)
			(layer "B.Fab")
		)
		(fp_line
			(start -0.120396 0.2794)
			(end 0.12065 0.2794)
			(stroke
				(width 0.1)
				(type default)
			)
			(layer "B.Fab")
		)
		(fp_line
			(start -0.12065 -0.2794)
			(end -0.12065 -0.3048)
			(stroke
				(width 0.1)
				(type default)
			)
			(layer "B.Fab")
		)
		(fp_line
			(start -0.12065 -0.3048)
			(end -0.67945 -0.3048)
			(stroke
				(width 0.1)
				(type default)
			)
			(layer "B.Fab")
		)
		(fp_line
			(start -0.67945 0.3048)
			(end -0.120396 0.3048)
			(stroke
				(width 0.1)
				(type default)
			)
			(layer "B.Fab")
		)
		(fp_line
			(start -0.67945 -0.3048)
			(end -0.67945 0.3048)
			(stroke
				(width 0.1)
				(type default)
			)
			(layer "B.Fab")
		)
		(pad "1" smd circle
			(at 0.40005 0)
			(size 0 0)
			(layers "B.Cu" "B.Mask" "B.Paste")
			(net "P3V3_AUX")
		)
		(pad "2" smd circle
			(at -0.40005 0)
			(size 0 0)
			(layers "B.Cu" "B.Mask" "B.Paste")
			(net "A_HSC_LOW_GATE")
		)
	)
)
